# S9S_MB_2U (Grand Teton) — schematic netlist excerpt (pin names and nets, part order shuffled) for the footprints in the layout excerpt that follows; sources: Cadence DE-HDL packaged netlist, KiCad conversion of 03242023_DA0F0TMBIJ0_F0T_Motherboard_J_brd_V01_OCP.brd

R4198  Q_RES  1K 1% EMPTY  pkg 0402LF  page 170 : A = P3V3_AUX ; B = U270_0_ADD1
PJ52  Q_SHORT  EMPTY  pkg SM  page 284 : \1\ = VSENSE_PVCCIN_CPU1_DP ; \2\ = SH_PVCCIN_CPU1
R1313  Q_RES  33.2 1% CHIP  pkg 0402LF  page 205 : A = FM_PCH_GLB_RST_WARN_N ; B = FM_PCH_PLD_GLB_RST_WARN_N

(kicad_pcb
	(version 20260206)
	(generator "pcbnew")
	(generator_version "10.0")
	(general
		(thickness 1.6)
		(legacy_teardrops no)
	)
	(paper "A4")
	(title_block
		(title "03242023_DA0F0TMBIJ0_F0T_Motherboard_J_brd_V01_OCP.brd")
		(comment 1 "Grand Teton / footprints 3331-3333 of 6105")
	)
	(layers
		(0 "F.Cu" signal "TOP")
		(4 "In1.Cu" signal "GND")
		(6 "In2.Cu" signal "IN1")
		(8 "In3.Cu" signal "GND1")
		(10 "In4.Cu" signal "IN2")
		(12 "In5.Cu" signal "GND2")
		(14 "In6.Cu" signal "IN3")
		(16 "In7.Cu" signal "GND3")
		(18 "In8.Cu" signal "VCC")
		(20 "In9.Cu" signal "VCC1")
		(22 "In10.Cu" signal "GND4")
		(24 "In11.Cu" signal "IN4")
		(26 "In12.Cu" signal "GND5")
		(28 "In13.Cu" signal "IN5")
		(30 "In14.Cu" signal "GND6")
		(32 "In15.Cu" signal "IN6")
		(34 "In16.Cu" signal "GND7")
		(2 "B.Cu" signal "BOTTOM")
		(9 "F.Adhes" user "F.Adhesive")
		(11 "B.Adhes" user "B.Adhesive")
		(13 "F.Paste" user "Package Geometry/Pastemask Top")
		(15 "B.Paste" user "Package Geometry/Pastemask Bottom")
		(5 "F.SilkS" user "Ref Des/Silkscreen Top")
		(7 "B.SilkS" user "Ref Des/Silkscreen Bottom")
		(1 "F.Mask" user "Board Geometry/Soldermask Top")
		(3 "B.Mask" user "Board Geometry/Soldermask Bottom")
		(17 "Dwgs.User" user "User.Drawings")
		(19 "Cmts.User" user "User.Comments")
		(21 "Eco1.User" user "User.Eco1")
		(23 "Eco2.User" user "User.Eco2")
		(25 "Edge.Cuts" user "Board Geometry/Outline")
		(27 "Margin" user)
		(31 "F.CrtYd" user "Package Geometry/Place Bound Top")
		(29 "B.CrtYd" user "Package Geometry/Place Bound Bottom")
		(35 "F.Fab" user "Ref Des/Assembly Top")
		(33 "B.Fab" user "Ref Des/Assembly Bottom")
	)
	(footprint ""
		(layer "F.Cu")
		(at 193.38036 -120.614948 180)
		(property "Reference" "R1313"
			(at 0 0 180)
			(layer "F.SilkS")
			(hide yes)
			(effects
				(font
					(size 1.27 1.27)
				)
			)
		)
		(property "Value" ""
			(at 0 0 180)
			(layer "F.Fab")
			(effects
				(font
					(size 1.27 1.27)
				)
			)
		)
		(duplicate_pad_numbers_are_jumpers no)
		(fp_line
			(start 0.7874 0.4064)
			(end -0.7874 0.4064)
			(stroke
				(width 0.1524)
				(type default)
			)
			(layer "F.SilkS")
		)
		(fp_line
			(start 0.7874 -0.4064)
			(end 0.7874 0.4064)
			(stroke
				(width 0.1524)
				(type default)
			)
			(layer "F.SilkS")
		)
		(fp_line
			(start -0.7874 0.4064)
			(end -0.7874 -0.4064)
			(stroke
				(width 0.1524)
				(type default)
			)
			(layer "F.SilkS")
		)
		(fp_line
			(start -0.7874 -0.4064)
			(end 0.7874 -0.4064)
			(stroke
				(width 0.1524)
				(type default)
			)
			(layer "F.SilkS")
		)
		(fp_line
			(start 0.67945 0.3048)
			(end 0.120396 0.3048)
			(stroke
				(width 0.1)
				(type default)
			)
			(layer "F.Fab")
		)
		(fp_line
			(start 0.67945 -0.3048)
			(end 0.67945 0.3048)
			(stroke
				(width 0.1)
				(type default)
			)
			(layer "F.Fab")
		)
		(fp_line
			(start 0.12065 -0.2794)
			(end 0.12065 -0.3048)
			(stroke
				(width 0.1)
				(type default)
			)
			(layer "F.Fab")
		)
		(fp_line
			(start 0.12065 -0.3048)
			(end 0.67945 -0.3048)
			(stroke
				(width 0.1)
				(type default)
			)
			(layer "F.Fab")
		)
		(fp_line
			(start 0.120396 0.3048)
			(end 0.120396 0.2794)
			(stroke
				(width 0.1)
				(type default)
			)
			(layer "F.Fab")
		)
		(fp_line
			(start 0.120396 0.2794)
			(end -0.12065 0.2794)
			(stroke
				(width 0.1)
				(type default)
			)
			(layer "F.Fab")
		)
		(fp_line
			(start -0.12065 0.3048)
			(end -0.67945 0.3048)
			(stroke
				(width 0.1)
				(type default)
			)
			(layer "F.Fab")
		)
		(fp_line
			(start -0.12065 0.2794)
			(end -0.12065 0.3048)
			(stroke
				(width 0.1)
				(type default)
			)
			(layer "F.Fab")
		)
		(fp_line
			(start -0.12065 -0.2794)
			(end 0.12065 -0.2794)
			(stroke
				(width 0.1)
				(type default)
			)
			(layer "F.Fab")
		)
		(fp_line
			(start -0.12065 -0.305054)
			(end -0.12065 -0.2794)
			(stroke
				(width 0.1)
				(type default)
			)
			(layer "F.Fab")
		)
		(fp_line
			(start -0.67945 0.3048)
			(end -0.67945 -0.305054)
			(stroke
				(width 0.1)
				(type default)
			)
			(layer "F.Fab")
		)
		(fp_line
			(start -0.67945 -0.305054)
			(end -0.12065 -0.305054)
			(stroke
				(width 0.1)
				(type default)
			)
			(layer "F.Fab")
		)
		(pad "1" smd circle
			(at -0.40005 0 180)
			(size 0 0)
			(layers "F.Cu" "F.Mask" "F.Paste")
			(net "FM_PCH_GLB_RST_WARN_N")
		)
		(pad "2" smd circle
			(at 0.40005 0 180)
			(size 0 0)
			(layers "F.Cu" "F.Mask" "F.Paste")
			(net "FM_PCH_PLD_GLB_RST_WARN_N")
		)
	)
	(footprint ""
		(layer "F.Cu")
		(at 370.618258 -417.17341 90)
		(property "Reference" "R4198"
			(at 0 0 90)
			(layer "F.SilkS")
			(hide yes)
			(effects
				(font
					(size 1.27 1.27)
				)
			)
		)
		(property "Value" ""
			(at 0 0 90)
			(layer "F.Fab")
			(effects
				(font
					(size 1.27 1.27)
				)
			)
		)
		(duplicate_pad_numbers_are_jumpers no)
		(fp_line
			(start 0.7874 -0.4064)
			(end 0.7874 0.4064)
			(stroke
				(width 0.1524)
				(type default)
			)
			(layer "F.SilkS")
		)
		(fp_line
			(start -0.7874 -0.4064)
			(end 0.7874 -0.4064)
			(stroke
				(width 0.1524)
				(type default)
			)
			(layer "F.SilkS")
		)
		(fp_line
			(start 0.7874 0.4064)
			(end -0.7874 0.4064)
			(stroke
				(width 0.1524)
				(type default)
			)
			(layer "F.SilkS")
		)
		(fp_line
			(start -0.7874 0.4064)
			(end -0.7874 -0.4064)
			(stroke
				(width 0.1524)
				(type default)
			)
			(layer "F.SilkS")
		)
		(fp_line
			(start -0.12065 -0.305054)
			(end -0.12065 -0.2794)
			(stroke
				(width 0.1)
				(type default)
			)
			(layer "F.Fab")
		)
		(fp_line
			(start -0.67945 -0.305054)
			(end -0.12065 -0.305054)
			(stroke
				(width 0.1)
				(type default)
			)
			(layer "F.Fab")
		)
		(fp_line
			(start 0.67945 -0.3048)
			(end 0.67945 0.3048)
			(stroke
				(width 0.1)
				(type default)
			)
			(layer "F.Fab")
		)
		(fp_line
			(start 0.12065 -0.3048)
			(end 0.67945 -0.3048)
			(stroke
				(width 0.1)
				(type default)
			)
			(layer "F.Fab")
		)
		(fp_line
			(start 0.12065 -0.2794)
			(end 0.12065 -0.3048)
			(stroke
				(width 0.1)
				(type default)
			)
			(layer "F.Fab")
		)
		(fp_line
			(start -0.12065 -0.2794)
			(end 0.12065 -0.2794)
			(stroke
				(width 0.1)
				(type default)
			)
			(layer "F.Fab")
		)
		(fp_line
			(start 0.120396 0.2794)
			(end -0.12065 0.2794)
			(stroke
				(width 0.1)
				(type default)
			)
			(layer "F.Fab")
		)
		(fp_line
			(start -0.12065 0.2794)
			(end -0.12065 0.3048)
			(stroke
				(width 0.1)
				(type default)
			)
			(layer "F.Fab")
		)
		(fp_line
			(start 0.67945 0.3048)
			(end 0.120396 0.3048)
			(stroke
				(width 0.1)
				(type default)
			)
			(layer "F.Fab")
		)
		(fp_line
			(start 0.120396 0.3048)
			(end 0.120396 0.2794)
			(stroke
				(width 0.1)
				(type default)
			)
			(layer "F.Fab")
		)
		(fp_line
			(start -0.12065 0.3048)
			(end -0.67945 0.3048)
			(stroke
				(width 0.1)
				(type default)
			)
			(layer "F.Fab")
		)
		(fp_line
			(start -0.67945 0.3048)
			(end -0.67945 -0.305054)
			(stroke
				(width 0.1)
				(type default)
			)
			(layer "F.Fab")
		)
		(pad "1" smd circle
			(at -0.40005 0 90)
			(size 0 0)
			(layers "F.Cu" "F.Mask" "F.Paste")
			(net "P3V3_AUX")
		)
		(pad "2" smd circle
			(at 0.40005 0 90)
			(size 0 0)
			(layers "F.Cu" "F.Mask" "F.Paste")
			(net "U270_0_ADD1")
		)
	)
	(footprint ""
		(layer "F.Cu")
		(at 102.818946 -352.02114 180)
		(property "Reference" "PJ52"
			(at 1.986788 -1.20904 0)
			(unlocked yes)
			(layer "F.SilkS")
			(effects
				(font
					(size 0.7874 0.5842)
					(thickness 0.1524)
				)
				(justify left)
			)
		)
		(property "Value" ""
			(at 0 0 180)
			(layer "F.Fab")
			(effects
				(font
					(size 1.27 1.27)
				)
			)
		)
		(duplicate_pad_numbers_are_jumpers no)
		(pad "1" smd circle
			(at -0.7493 0 270)
			(size 0 0)
			(layers "F.Cu" "F.Mask" "F.Paste")
			(net "VSENSE_PVCCIN_CPU1_DP")
		)
		(pad "2" smd rect
			(at 0.7493 0 90)
			(size 0.7112 0.8128)
			(layers "F.Cu" "F.Mask" "F.Paste")
			(net "SH_PVCCIN_CPU1")
		)
		(zone
			(layer "F.Cu")
			(hatch none 0.5)
			(connect_pads
				(clearance 0)
			)
			(min_thickness 0.25)
			(keepout
				(tracks allowed)
				(vias not_allowed)
				(pads allowed)
				(copperpour not_allowed)
				(footprints allowed)
			)
			(placement
				(enabled no)
				(sheetname "")
			)
			(fill
				(thermal_gap 0.5)
				(thermal_bridge_width 0.5)
				(island_removal_mode 0)
			)
			(polygon
				(pts
					(xy 101.612446 -351.61474) (xy 104.000046 -351.61474) (xy 104.000046 -352.432366) (xy 101.612446 -352.432366)
				)
			)
		)
	)
)
